(kicad_pcb
	(version 20260206)
	(generator "pcbnew")
	(generator_version "10.0")
	(general
		(thickness 1.6)
		(legacy_teardrops no)
	)
	(paper "A4")
	(title_block
		(title "9054_F0T_PDB_BD_GPU_F_V04_1213_1550_OCP.brd")
		(comment 1 "Grand Teton / footprints 527-532 of 608")
	)
	(layers
		(0 "F.Cu" signal "TOP")
		(4 "In1.Cu" signal "GND")
		(6 "In2.Cu" signal "IN1")
		(8 "In3.Cu" signal "GND1")
		(10 "In4.Cu" signal "VCC")
		(12 "In5.Cu" signal "VCC1")
		(14 "In6.Cu" signal "GND2")
		(16 "In7.Cu" signal "IN2")
		(18 "In8.Cu" signal "GND3")
		(2 "B.Cu" signal "BOTTOM")
		(9 "F.Adhes" user "F.Adhesive")
		(11 "B.Adhes" user "B.Adhesive")
		(13 "F.Paste" user "Package Geometry/Pastemask Top")
		(15 "B.Paste" user "Package Geometry/Pastemask Bottom")
		(5 "F.SilkS" user "Ref Des/Silkscreen Top")
		(7 "B.SilkS" user "Ref Des/Silkscreen Bottom")
		(1 "F.Mask" user "Board Geometry/Soldermask Top")
		(3 "B.Mask" user "Board Geometry/Soldermask Bottom")
		(17 "Dwgs.User" user "User.Drawings")
		(19 "Cmts.User" user "User.Comments")
		(21 "Eco1.User" user "User.Eco1")
		(23 "Eco2.User" user "User.Eco2")
		(25 "Edge.Cuts" user "Board Geometry/Outline")
		(27 "Margin" user)
		(31 "F.CrtYd" user "Package Geometry/Place Bound Top")
		(29 "B.CrtYd" user "Package Geometry/Place Bound Bottom")
		(35 "F.Fab" user "Ref Des/Assembly Top")
		(33 "B.Fab" user "Ref Des/Assembly Bottom")
	)
	(footprint ""
		(layer "B.Cu")
		(at 161.717736 -73.279)
		(property "Reference" "PR7013"
			(at 0 0 0)
			(layer "B.SilkS")
			(hide yes)
			(effects
				(font
					(size 1.27 1.27)
				)
				(justify mirror)
			)
		)
		(property "Value" ""
			(at 0 0 0)
			(layer "B.Fab")
			(effects
				(font
					(size 1.27 1.27)
				)
				(justify mirror)
			)
		)
		(duplicate_pad_numbers_are_jumpers no)
		(fp_line
			(start -0.7874 -0.4064)
			(end -0.7874 0.4064)
			(stroke
				(width 0.1524)
				(type default)
			)
			(layer "B.SilkS")
		)
		(fp_line
			(start -0.7874 0.4064)
			(end 0.7874 0.4064)
			(stroke
				(width 0.1524)
				(type default)
			)
			(layer "B.SilkS")
		)
		(fp_line
			(start 0.7874 -0.4064)
			(end -0.7874 -0.4064)
			(stroke
				(width 0.1524)
				(type default)
			)
			(layer "B.SilkS")
		)
		(fp_line
			(start 0.7874 0.4064)
			(end 0.7874 -0.4064)
			(stroke
				(width 0.1524)
				(type default)
			)
			(layer "B.SilkS")
		)
		(fp_line
			(start -0.67945 -0.3048)
			(end -0.67945 0.3048)
			(stroke
				(width 0.1)
				(type default)
			)
			(layer "B.Fab")
		)
		(fp_line
			(start -0.67945 0.3048)
			(end -0.120396 0.3048)
			(stroke
				(width 0.1)
				(type default)
			)
			(layer "B.Fab")
		)
		(fp_line
			(start -0.12065 -0.3048)
			(end -0.67945 -0.3048)
			(stroke
				(width 0.1)
				(type default)
			)
			(layer "B.Fab")
		)
		(fp_line
			(start -0.12065 -0.2794)
			(end -0.12065 -0.3048)
			(stroke
				(width 0.1)
				(type default)
			)
			(layer "B.Fab")
		)
		(fp_line
			(start -0.120396 0.2794)
			(end 0.12065 0.2794)
			(stroke
				(width 0.1)
				(type default)
			)
			(layer "B.Fab")
		)
		(fp_line
			(start -0.120396 0.3048)
			(end -0.120396 0.2794)
			(stroke
				(width 0.1)
				(type default)
			)
			(layer "B.Fab")
		)
		(fp_line
			(start 0.12065 -0.305054)
			(end 0.12065 -0.2794)
			(stroke
				(width 0.1)
				(type default)
			)
			(layer "B.Fab")
		)
		(fp_line
			(start 0.12065 -0.2794)
			(end -0.12065 -0.2794)
			(stroke
				(width 0.1)
				(type default)
			)
			(layer "B.Fab")
		)
		(fp_line
			(start 0.12065 0.2794)
			(end 0.12065 0.3048)
			(stroke
				(width 0.1)
				(type default)
			)
			(layer "B.Fab")
		)
		(fp_line
			(start 0.12065 0.3048)
			(end 0.67945 0.3048)
			(stroke
				(width 0.1)
				(type default)
			)
			(layer "B.Fab")
		)
		(fp_line
			(start 0.67945 -0.305054)
			(end 0.12065 -0.305054)
			(stroke
				(width 0.1)
				(type default)
			)
			(layer "B.Fab")
		)
		(fp_line
			(start 0.67945 0.3048)
			(end 0.67945 -0.305054)
			(stroke
				(width 0.1)
				(type default)
			)
			(layer "B.Fab")
		)
		(pad "1" smd circle
			(at 0.40005 0 180)
			(size 0 0)
			(layers "B.Cu" "B.Mask" "B.Paste")
			(net "GND1_FIELD_SIGNAL")
		)
		(pad "2" smd circle
			(at -0.40005 0 180)
			(size 0 0)
			(layers "B.Cu" "B.Mask" "B.Paste")
			(net "P52V_HS2_CLKIN")
		)
	)
	(footprint ""
		(layer "B.Cu")
		(at 441.325 -45.974 180)
		(property "Reference" "R5940"
			(at 0 0 0)
			(layer "B.SilkS")
			(hide yes)
			(effects
				(font
					(size 1.27 1.27)
				)
				(justify mirror)
			)
		)
		(property "Value" ""
			(at 0 0 0)
			(layer "B.Fab")
			(effects
				(font
					(size 1.27 1.27)
				)
				(justify mirror)
			)
		)
		(duplicate_pad_numbers_are_jumpers no)
		(fp_line
			(start 0.7874 0.4064)
			(end 0.7874 -0.4064)
			(stroke
				(width 0.1524)
				(type default)
			)
			(layer "B.SilkS")
		)
		(fp_line
			(start 0.7874 -0.4064)
			(end -0.7874 -0.4064)
			(stroke
				(width 0.1524)
				(type default)
			)
			(layer "B.SilkS")
		)
		(fp_line
			(start -0.7874 0.4064)
			(end 0.7874 0.4064)
			(stroke
				(width 0.1524)
				(type default)
			)
			(layer "B.SilkS")
		)
		(fp_line
			(start -0.7874 -0.4064)
			(end -0.7874 0.4064)
			(stroke
				(width 0.1524)
				(type default)
			)
			(layer "B.SilkS")
		)
		(fp_line
			(start 0.67945 0.3048)
			(end 0.67945 -0.305054)
			(stroke
				(width 0.1)
				(type default)
			)
			(layer "B.Fab")
		)
		(fp_line
			(start 0.67945 -0.305054)
			(end 0.12065 -0.305054)
			(stroke
				(width 0.1)
				(type default)
			)
			(layer "B.Fab")
		)
		(fp_line
			(start 0.12065 0.3048)
			(end 0.67945 0.3048)
			(stroke
				(width 0.1)
				(type default)
			)
			(layer "B.Fab")
		)
		(fp_line
			(start 0.12065 0.2794)
			(end 0.12065 0.3048)
			(stroke
				(width 0.1)
				(type default)
			)
			(layer "B.Fab")
		)
		(fp_line
			(start 0.12065 -0.2794)
			(end -0.12065 -0.2794)
			(stroke
				(width 0.1)
				(type default)
			)
			(layer "B.Fab")
		)
		(fp_line
			(start 0.12065 -0.305054)
			(end 0.12065 -0.2794)
			(stroke
				(width 0.1)
				(type default)
			)
			(layer "B.Fab")
		)
		(fp_line
			(start -0.120396 0.3048)
			(end -0.120396 0.2794)
			(stroke
				(width 0.1)
				(type default)
			)
			(layer "B.Fab")
		)
		(fp_line
			(start -0.120396 0.2794)
			(end 0.12065 0.2794)
			(stroke
				(width 0.1)
				(type default)
			)
			(layer "B.Fab")
		)
		(fp_line
			(start -0.12065 -0.2794)
			(end -0.12065 -0.3048)
			(stroke
				(width 0.1)
				(type default)
			)
			(layer "B.Fab")
		)
		(fp_line
			(start -0.12065 -0.3048)
			(end -0.67945 -0.3048)
			(stroke
				(width 0.1)
				(type default)
			)
			(layer "B.Fab")
		)
		(fp_line
			(start -0.67945 0.3048)
			(end -0.120396 0.3048)
			(stroke
				(width 0.1)
				(type default)
			)
			(layer "B.Fab")
		)
		(fp_line
			(start -0.67945 -0.3048)
			(end -0.67945 0.3048)
			(stroke
				(width 0.1)
				(type default)
			)
			(layer "B.Fab")
		)
		(pad "1" smd circle
			(at 0.40005 0)
			(size 0 0)
			(layers "B.Cu" "B.Mask" "B.Paste")
			(net "FAN_PWR_EN_BUF")
		)
		(pad "2" smd circle
			(at -0.40005 0)
			(size 0 0)
			(layers "B.Cu" "B.Mask" "B.Paste")
			(net "FAN_PWR_EN_BUF_R")
		)
	)
	(footprint ""
		(layer "B.Cu")
		(at 170.734736 -63.754 90)
		(property "Reference" "PC612"
			(at 0 0 90)
			(layer "B.SilkS")
			(hide yes)
			(effects
				(font
					(size 1.27 1.27)
				)
				(justify mirror)
			)
		)
		(property "Value" ""
			(at 0 0 90)
			(layer "B.Fab")
			(effects
				(font
					(size 1.27 1.27)
				)
				(justify mirror)
			)
		)
		(duplicate_pad_numbers_are_jumpers no)
		(fp_line
			(start 0.7874 -0.4064)
			(end -0.7874 -0.4064)
			(stroke
				(width 0.1524)
				(type default)
			)
			(layer "B.SilkS")
		)
		(fp_line
			(start -0.7874 -0.4064)
			(end -0.7874 0.4064)
			(stroke
				(width 0.1524)
				(type default)
			)
			(layer "B.SilkS")
		)
		(fp_line
			(start 0.7874 0.4064)
			(end 0.7874 -0.4064)
			(stroke
				(width 0.1524)
				(type default)
			)
			(layer "B.SilkS")
		)
		(fp_line
			(start -0.7874 0.4064)
			(end 0.7874 0.4064)
			(stroke
				(width 0.1524)
				(type default)
			)
			(layer "B.SilkS")
		)
		(fp_line
			(start 0.67945 -0.305054)
			(end 0.12065 -0.305054)
			(stroke
				(width 0.1)
				(type default)
			)
			(layer "B.Fab")
		)
		(fp_line
			(start 0.12065 -0.305054)
			(end 0.12065 -0.2794)
			(stroke
				(width 0.1)
				(type default)
			)
			(layer "B.Fab")
		)
		(fp_line
			(start -0.12065 -0.3048)
			(end -0.67945 -0.3048)
			(stroke
				(width 0.1)
				(type default)
			)
			(layer "B.Fab")
		)
		(fp_line
			(start -0.67945 -0.3048)
			(end -0.67945 0.3048)
			(stroke
				(width 0.1)
				(type default)
			)
			(layer "B.Fab")
		)
		(fp_line
			(start 0.12065 -0.2794)
			(end -0.12065 -0.2794)
			(stroke
				(width 0.1)
				(type default)
			)
			(layer "B.Fab")
		)
		(fp_line
			(start -0.12065 -0.2794)
			(end -0.12065 -0.3048)
			(stroke
				(width 0.1)
				(type default)
			)
			(layer "B.Fab")
		)
		(fp_line
			(start 0.12065 0.2794)
			(end 0.12065 0.3048)
			(stroke
				(width 0.1)
				(type default)
			)
			(layer "B.Fab")
		)
		(fp_line
			(start -0.120396 0.2794)
			(end 0.12065 0.2794)
			(stroke
				(width 0.1)
				(type default)
			)
			(layer "B.Fab")
		)
		(fp_line
			(start 0.67945 0.3048)
			(end 0.67945 -0.305054)
			(stroke
				(width 0.1)
				(type default)
			)
			(layer "B.Fab")
		)
		(fp_line
			(start 0.12065 0.3048)
			(end 0.67945 0.3048)
			(stroke
				(width 0.1)
				(type default)
			)
			(layer "B.Fab")
		)
		(fp_line
			(start -0.120396 0.3048)
			(end -0.120396 0.2794)
			(stroke
				(width 0.1)
				(type default)
			)
			(layer "B.Fab")
		)
		(fp_line
			(start -0.67945 0.3048)
			(end -0.120396 0.3048)
			(stroke
				(width 0.1)
				(type default)
			)
			(layer "B.Fab")
		)
		(pad "1" smd circle
			(at 0.40005 0 270)
			(size 0 0)
			(layers "B.Cu" "B.Mask" "B.Paste")
			(net "P52V_HS2_RND")
		)
		(pad "2" smd circle
			(at -0.40005 0 270)
			(size 0 0)
			(layers "B.Cu" "B.Mask" "B.Paste")
			(net "GND1_FIELD_SIGNAL")
		)
	)
	(footprint ""
		(layer "B.Cu")
		(at 252.476 -40.259 90)
		(property "Reference" "FS5"
			(at 3.937 2.64033 270)
			(unlocked yes)
			(layer "B.SilkS")
			(effects
				(font
					(size 0.7874 0.5842)
					(thickness 0.1524)
				)
				(justify left mirror)
			)
		)
		(property "Value" ""
			(at 0 0 90)
			(layer "B.Fab")
			(effects
				(font
					(size 1.27 1.27)
				)
				(justify mirror)
			)
		)
		(duplicate_pad_numbers_are_jumpers no)
		(fp_line
			(start 6.427724 -1.8415)
			(end 6.427724 1.8415)
			(stroke
				(width 0.1524)
				(type default)
			)
			(layer "B.SilkS")
		)
		(fp_line
			(start -6.427724 -1.8415)
			(end 6.427724 -1.8415)
			(stroke
				(width 0.1524)
				(type default)
			)
			(layer "B.SilkS")
		)
		(fp_line
			(start 6.427724 1.8415)
			(end -6.427724 1.8415)
			(stroke
				(width 0.1524)
				(type default)
			)
			(layer "B.SilkS")
		)
		(fp_line
			(start -6.427724 1.8415)
			(end -6.427724 -1.8415)
			(stroke
				(width 0.1524)
				(type default)
			)
			(layer "B.SilkS")
		)
		(fp_line
			(start 5.225034 -1.610106)
			(end -5.225034 -1.610106)
			(stroke
				(width 0.1)
				(type default)
			)
			(layer "B.Fab")
		)
		(fp_line
			(start -5.225034 -1.610106)
			(end -5.225034 1.610106)
			(stroke
				(width 0.1)
				(type default)
			)
			(layer "B.Fab")
		)
		(fp_line
			(start 5.225034 1.610106)
			(end 5.225034 -1.610106)
			(stroke
				(width 0.1)
				(type default)
			)
			(layer "B.Fab")
		)
		(fp_line
			(start -5.225034 1.610106)
			(end 5.225034 1.610106)
			(stroke
				(width 0.1)
				(type default)
			)
			(layer "B.Fab")
		)
		(pad "1" smd rect
			(at 4.675124 0 270)
			(size 3.2512 3.429)
			(layers "B.Cu" "B.Mask" "B.Paste")
			(net "P52V_1_FUSE_1")
		)
		(pad "2" smd rect
			(at -4.675124 0 270)
			(size 3.2512 3.429)
			(layers "B.Cu" "B.Mask" "B.Paste")
			(net "P52V_1")
		)
	)
	(footprint ""
		(layer "B.Cu")
		(at 278.4094 -62.865 180)
		(property "Reference" "R151"
			(at 0 0 0)
			(layer "B.SilkS")
			(hide yes)
			(effects
				(font
					(size 1.27 1.27)
				)
				(justify mirror)
			)
		)
		(property "Value" ""
			(at 0 0 0)
			(layer "B.Fab")
			(effects
				(font
					(size 1.27 1.27)
				)
				(justify mirror)
			)
		)
		(duplicate_pad_numbers_are_jumpers no)
		(fp_line
			(start 0.7874 0.4064)
			(end 0.7874 -0.4064)
			(stroke
				(width 0.1524)
				(type default)
			)
			(layer "B.SilkS")
		)
		(fp_line
			(start 0.7874 -0.4064)
			(end -0.7874 -0.4064)
			(stroke
				(width 0.1524)
				(type default)
			)
			(layer "B.SilkS")
		)
		(fp_line
			(start -0.7874 0.4064)
			(end 0.7874 0.4064)
			(stroke
				(width 0.1524)
				(type default)
			)
			(layer "B.SilkS")
		)
		(fp_line
			(start -0.7874 -0.4064)
			(end -0.7874 0.4064)
			(stroke
				(width 0.1524)
				(type default)
			)
			(layer "B.SilkS")
		)
		(fp_line
			(start 0.67945 0.3048)
			(end 0.67945 -0.305054)
			(stroke
				(width 0.1)
				(type default)
			)
			(layer "B.Fab")
		)
		(fp_line
			(start 0.67945 -0.305054)
			(end 0.12065 -0.305054)
			(stroke
				(width 0.1)
				(type default)
			)
			(layer "B.Fab")
		)
		(fp_line
			(start 0.12065 0.3048)
			(end 0.67945 0.3048)
			(stroke
				(width 0.1)
				(type default)
			)
			(layer "B.Fab")
		)
		(fp_line
			(start 0.12065 0.2794)
			(end 0.12065 0.3048)
			(stroke
				(width 0.1)
				(type default)
			)
			(layer "B.Fab")
		)
		(fp_line
			(start 0.12065 -0.2794)
			(end -0.12065 -0.2794)
			(stroke
				(width 0.1)
				(type default)
			)
			(layer "B.Fab")
		)
		(fp_line
			(start 0.12065 -0.305054)
			(end 0.12065 -0.2794)
			(stroke
				(width 0.1)
				(type default)
			)
			(layer "B.Fab")
		)
		(fp_line
			(start -0.120396 0.3048)
			(end -0.120396 0.2794)
			(stroke
				(width 0.1)
				(type default)
			)
			(layer "B.Fab")
		)
		(fp_line
			(start -0.120396 0.2794)
			(end 0.12065 0.2794)
			(stroke
				(width 0.1)
				(type default)
			)
			(layer "B.Fab")
		)
		(fp_line
			(start -0.12065 -0.2794)
			(end -0.12065 -0.3048)
			(stroke
				(width 0.1)
				(type default)
			)
			(layer "B.Fab")
		)
		(fp_line
			(start -0.12065 -0.3048)
			(end -0.67945 -0.3048)
			(stroke
				(width 0.1)
				(type default)
			)
			(layer "B.Fab")
		)
		(fp_line
			(start -0.67945 0.3048)
			(end -0.120396 0.3048)
			(stroke
				(width 0.1)
				(type default)
			)
			(layer "B.Fab")
		)
		(fp_line
			(start -0.67945 -0.3048)
			(end -0.67945 0.3048)
			(stroke
				(width 0.1)
				(type default)
			)
			(layer "B.Fab")
		)
		(pad "1" smd circle
			(at 0.40005 0)
			(size 0 0)
			(layers "B.Cu" "B.Mask" "B.Paste")
			(net "P52V_HS1_GPO2")
		)
		(pad "2" smd circle
			(at -0.40005 0)
			(size 0 0)
			(layers "B.Cu" "B.Mask" "B.Paste")
			(net "P52V_HS1_FLT")
		)
	)
	(footprint ""
		(layer "B.Cu")
		(at 270.0274 -59.817 -90)
		(property "Reference" "PR17"
			(at 0 0 90)
			(layer "B.SilkS")
			(hide yes)
			(effects
				(font
					(size 1.27 1.27)
				)
				(justify mirror)
			)
		)
		(property "Value" ""
			(at 0 0 90)
			(layer "B.Fab")
			(effects
				(font
					(size 1.27 1.27)
				)
				(justify mirror)
			)
		)
		(duplicate_pad_numbers_are_jumpers no)
		(fp_line
			(start -1.651 0.8382)
			(end 1.651 0.8382)
			(stroke
				(width 0.1524)
				(type default)
			)
			(layer "B.SilkS")
		)
		(fp_line
			(start 1.651 0.8382)
			(end 1.651 -0.8382)
			(stroke
				(width 0.1524)
				(type default)
			)
			(layer "B.SilkS")
		)
		(fp_line
			(start -1.651 -0.8382)
			(end -1.651 0.8382)
			(stroke
				(width 0.1524)
				(type default)
			)
			(layer "B.SilkS")
		)
		(fp_line
			(start 1.651 -0.8382)
			(end -1.651 -0.8382)
			(stroke
				(width 0.1524)
				(type default)
			)
			(layer "B.SilkS")
		)
		(fp_line
			(start -1.560576 0.7366)
			(end -1.560576 -0.7366)
			(stroke
				(width 0.1)
				(type default)
			)
			(layer "B.Fab")
		)
		(fp_line
			(start -1.524 0.7366)
			(end -1.560576 0.7366)
			(stroke
				(width 0.1)
				(type default)
			)
			(layer "B.Fab")
		)
		(fp_line
			(start 1.524 0.7366)
			(end -1.524 0.7366)
			(stroke
				(width 0.1)
				(type default)
			)
			(layer "B.Fab")
		)
		(fp_line
			(start 1.559814 0.7366)
			(end 1.524 0.7366)
			(stroke
				(width 0.1)
				(type default)
			)
			(layer "B.Fab")
		)
		(fp_line
			(start -1.560576 -0.7366)
			(end -1.524 -0.7366)
			(stroke
				(width 0.1)
				(type default)
			)
			(layer "B.Fab")
		)
		(fp_line
			(start -1.524 -0.7366)
			(end 1.524 -0.7366)
			(stroke
				(width 0.1)
				(type default)
			)
			(layer "B.Fab")
		)
		(fp_line
			(start 1.524 -0.7366)
			(end 1.559814 -0.7366)
			(stroke
				(width 0.1)
				(type default)
			)
			(layer "B.Fab")
		)
		(fp_line
			(start 1.559814 -0.7366)
			(end 1.559814 0.7366)
			(stroke
				(width 0.1)
				(type default)
			)
			(layer "B.Fab")
		)
		(pad "1" smd rect
			(at 0.94996 0 270)
			(size 1.1176 1.3716)
			(layers "B.Cu" "B.Mask" "B.Paste")
			(net "P52V_HS1")
		)
		(pad "2" smd rect
			(at -0.94996 0 270)
			(size 1.1176 1.3716)
			(layers "B.Cu" "B.Mask" "B.Paste")
			(net "P52V_HS1_PWRGIN")
		)
	)
)
